FILE_TYPE = CONNECTIVITY;
{Allegro Design Entry HDL 16.6-p007 (v16-6-112F) 10/10/2012}
"PAGE_NUMBER" = 53;
0"NC";
1"M_F_DQS_DP<17:0>";
2"M_F_DQS_DN<17:0>";
3"M_F_DQ<63:0>";
4"M_F_MA<17:0>";
5"M_F_CLK_DP<3:0>";
6"M_F_BG<1:0>";
7"M_F_BA<1:0>";
8"M_F_CS_N<7:0>";
9"M_F_CKE<3:0>";
10"M_F_ECC<7:0>";
11"M_F_ODT<3:0>";
12"M_F_CLK_DN<3:0>";
13"PVTT_DEF\g";
14"PVDDQ_DEF\g";
15"GND\g";
16"GND\g";
17"GND\g";
18"PVPP_DEF\g";
19"PVPP_DEF\g";
20"P12V_NVDIMM_DEF\g";
21"GND\g";
22"M_F_VREF";
23"TP_CH_F_DIMM_F0_RFU_1";
24"TP_CH_F_DIMM_F0_RFU_0";
25"TP_CH_F_DIMM_F0_RFU_2";
26"M_F_ACT_N";
27"M_F_ALERT_N";
28"SMB_DDR_DEF_VPP_SCL";
29"SMB_DDR_DEF_VPP_SDA";
30"FM_ADR_COMPLETE_DEF_N";
31"M_DEF_RST_N";
32"FM_DIMM_EVENT_COD_N";
33"M_F_PAR";
34"M_F_CLK_DN<0>";
35"M_F_CLK_DN<1>";
36"M_F_ODT<0>";
37"M_F_ECC<6>";
38"M_F_ECC<1>";
39"M_F_ECC<0>";
40"M_F_ECC<3>";
41"M_F_ECC<2>";
42"M_F_ECC<5>";
43"M_F_ECC<4>";
44"M_F_ECC<7>";
45"M_F_CS_N<0>";
46"M_F_CKE<0>";
47"M_F_ODT<1>";
48"M_F_CKE<1>";
49"M_F_CS_N<1>";
50"M_F_CS_N<2>";
51"M_F_CS_N<3>";
52"M_F_C<2>";
53"M_F_BA<0>";
54"M_F_BG<1>";
55"M_F_BG<0>";
56"M_F_CLK_DP<1>";
57"M_F_CLK_DP<0>";
58"M_F_BA<1>";
59"M_F_MA<2>";
60"M_F_MA<9>";
61"M_F_MA<8>";
62"M_F_MA<7>";
63"M_F_MA<6>";
64"M_F_MA<5>";
65"M_F_MA<4>";
66"M_F_MA<3>";
67"M_F_MA<1>";
68"M_F_MA<0>";
69"M_F_DQ<5>";
70"M_F_DQ<2>";
71"M_F_DQ<3>";
72"M_F_DQ<1>";
73"M_F_DQ<0>";
74"M_F_DQ<4>";
75"M_F_DQ<7>";
76"M_F_DQ<6>";
77"M_F_DQ<9>";
78"M_F_DQ<8>";
79"M_F_DQ<10>";
80"M_F_DQ<12>";
81"M_F_DQ<15>";
82"M_F_DQ<11>";
83"M_F_DQ<13>";
84"M_F_DQ<16>";
85"M_F_DQ<14>";
86"M_F_DQ<17>";
87"M_F_DQ<20>";
88"M_F_DQ<23>";
89"M_F_DQ<22>";
90"M_F_DQ<19>";
91"M_F_DQ<18>";
92"M_F_DQ<21>";
93"M_F_DQ<25>";
94"M_F_DQ<27>";
95"M_F_DQ<26>";
96"M_F_DQ<24>";
97"M_F_DQ<31>";
98"M_F_DQ<30>";
99"M_F_DQ<33>";
100"M_F_DQ<32>";
101"M_F_DQ<35>";
102"M_F_DQ<29>";
103"M_F_DQ<28>";
104"M_F_DQ<39>";
105"M_F_DQ<37>";
106"M_F_DQ<34>";
107"M_F_DQ<36>";
108"M_F_DQ<38>";
109"M_F_DQ<41>";
110"M_F_DQ<40>";
111"M_F_DQ<43>";
112"M_F_DQ<42>";
113"M_F_DQ<45>";
114"M_F_DQ<44>";
115"M_F_DQ<46>";
116"M_F_DQ<49>";
117"M_F_DQ<48>";
118"M_F_DQ<51>";
119"M_F_DQ<50>";
120"M_F_DQ<53>";
121"M_F_DQ<52>";
122"M_F_DQ<55>";
123"M_F_DQ<47>";
124"M_F_DQ<54>";
125"M_F_MA<16>";
126"M_F_MA<15>";
127"M_F_MA<14>";
128"M_F_MA<11>";
129"M_F_MA<10>";
130"M_F_MA<17>";
131"M_F_MA<13>";
132"M_F_MA<12>";
133"M_F_DQ<62>";
134"M_F_DQ<63>";
135"M_F_DQ<60>";
136"M_F_DQ<59>";
137"M_F_DQ<56>";
138"M_F_DQ<57>";
139"M_F_DQ<58>";
140"M_F_DQ<61>";
141"M_F_DQS_DN<6>";
142"M_F_DQS_DP<5>";
143"M_F_DQS_DN<5>";
144"M_F_DQS_DP<4>";
145"M_F_DQS_DN<4>";
146"M_F_DQS_DP<3>";
147"M_F_DQS_DN<3>";
148"M_F_DQS_DP<2>";
149"M_F_DQS_DN<2>";
150"M_F_DQS_DP<1>";
151"M_F_DQS_DN<1>";
152"M_F_DQS_DP<0>";
153"M_F_DQS_DN<0>";
154"M_F_DQS_DP<9>";
155"M_F_DQS_DN<9>";
156"M_F_DQS_DP<8>";
157"M_F_DQS_DN<8>";
158"M_F_DQS_DP<7>";
159"M_F_DQS_DN<7>";
160"M_F_DQS_DP<6>";
161"M_F_DQS_DP<16>";
162"M_F_DQS_DN<16>";
163"M_F_DQS_DP<15>";
164"M_F_DQS_DN<15>";
165"M_F_DQS_DP<14>";
166"M_F_DQS_DN<14>";
167"M_F_DQS_DP<13>";
168"M_F_DQS_DN<13>";
169"M_F_DQS_DP<12>";
170"M_F_DQS_DN<12>";
171"M_F_DQS_DP<11>";
172"M_F_DQS_DN<11>";
173"M_F_DQS_DP<10>";
174"M_F_DQS_DN<10>";
175"M_F_DQS_DP<17>";
176"M_F_DQS_DN<17>";
%"TAP"
"6","(650,5100)","2","mstr_standard","I10";
;
HDL_TAP"TRUE"
BODY_TYPE"PLUMBING"
CDS_LIB"mstr_standard";
"B \NAC \NWC"1;
"S \NAC"
BN"16"161;
%"TAP"
"6","(-1550,1825)","2","mstr_standard","I100";
;
HDL_TAP"TRUE"
BODY_TYPE"PLUMBING"
CDS_LIB"mstr_standard";
"B \NAC \NWC"3;
"S \NAC"
BN"11"82;
%"TAP"
"6","(-1550,1775)","2","mstr_standard","I101";
;
HDL_TAP"TRUE"
BODY_TYPE"PLUMBING"
CDS_LIB"mstr_standard";
"B \NAC \NWC"3;
"S \NAC"
BN"8"78;
%"TAP"
"6","(-1550,1675)","2","mstr_standard","I102";
;
HDL_TAP"TRUE"
BODY_TYPE"PLUMBING"
CDS_LIB"mstr_standard";
"B \NAC \NWC"3;
"S \NAC"
BN"6"76;
%"TAP"
"6","(-1550,1725)","2","mstr_standard","I103";
;
HDL_TAP"TRUE"
BODY_TYPE"PLUMBING"
CDS_LIB"mstr_standard";
"B \NAC \NWC"3;
"S \NAC"
BN"9"77;
%"TAP"
"6","(-1550,1625)","2","mstr_standard","I104";
;
HDL_TAP"TRUE"
BODY_TYPE"PLUMBING"
CDS_LIB"mstr_standard";
"B \NAC \NWC"3;
"S \NAC"
BN"7"75;
%"TAP"
"6","(-1550,1575)","2","mstr_standard","I105";
;
HDL_TAP"TRUE"
BODY_TYPE"PLUMBING"
CDS_LIB"mstr_standard";
"B \NAC \NWC"3;
"S \NAC"
BN"4"74;
%"TAP"
"6","(-1550,1475)","2","mstr_standard","I106";
;
HDL_TAP"TRUE"
BODY_TYPE"PLUMBING"
CDS_LIB"mstr_standard";
"B \NAC \NWC"3;
"S \NAC"
BN"2"70;
%"TAP"
"6","(-1550,1525)","2","mstr_standard","I107";
;
HDL_TAP"TRUE"
BODY_TYPE"PLUMBING"
CDS_LIB"mstr_standard";
"B \NAC \NWC"3;
"S \NAC"
BN"5"69;
%"TAP"
"6","(-1550,1375)","2","mstr_standard","I108";
;
HDL_TAP"TRUE"
BODY_TYPE"PLUMBING"
CDS_LIB"mstr_standard";
"B \NAC \NWC"3;
"S \NAC"
BN"0"73;
%"TAP"
"6","(-1550,1425)","2","mstr_standard","I109";
;
HDL_TAP"TRUE"
BODY_TYPE"PLUMBING"
CDS_LIB"mstr_standard";
"B \NAC \NWC"3;
"S \NAC"
BN"3"71;
%"TAP"
"6","(650,5000)","2","mstr_standard","I11";
;
HDL_TAP"TRUE"
BODY_TYPE"PLUMBING"
CDS_LIB"mstr_standard";
"B \NAC \NWC"1;
"S \NAC"
BN"15"163;
%"TAP"
"6","(-1550,1325)","2","mstr_standard","I110";
;
HDL_TAP"TRUE"
BODY_TYPE"PLUMBING"
CDS_LIB"mstr_standard";
"B \NAC \NWC"3;
"S \NAC"
BN"1"72;
%"SCONN288_H44441004"
"1","(-2300,2825)","0","mstr_sconn","I111";
;
CDS_SEC"1"
ROOM"DDR4_CH_F"
CDS_LOCATION"J4A1"
SEC"1"
SEC_TYPE"PIP"
CDS_LIB"mstr_sconn"
BOM_COST"MEM"
PACK_TYPE"PIP"
MATERIAL"SCONN"
PART_NUMBER"H44441-004"
LOCATION"J4A1";
"DQ<63>"
$PN"280"133;
"DQ<62>"
$PN"135"134;
"DQ<61>"
$PN"273"135;
"DQ<5>"
$PN"148"74;
"DQ<4>"
$PN"3"69;
"DQ<3>"
$PN"157"70;
"DQ<2>"
$PN"12"71;
"DQ<47>"
$PN"258"115;
"DQ<48>"
$PN"119"116;
"DQ<49>"
$PN"264"117;
"DQ<50>"
$PN"126"118;
"DQ<51>"
$PN"271"119;
"DQ<52>"
$PN"117"120;
"DQ<53>"
$PN"262"121;
"DQ<54>"
$PN"124"122;
"DQ<58>"
$PN"137"136;
"DQ<57>"
$PN"275"137;
"SAVE_N_NC"
$PN"230"30;
"RFU<1>"
$PN"227"23;
"RFU<0>"
$PN"205"24;
"DQ<17>"
$PN"172"84;
"DQ<15>"
$PN"166"85;
"DQ<26>"
$PN"45"94;
"DQ<27>"
$PN"190"95;
"S0_N"
$PN"84"45;
"CKE<0>"
$PN"60"46;
"ODT<1>"
$PN"91"47;
"ODT<0>"
$PN"87"36;
"CB<7>"
$PN"199"37;
"A16_RAS_N"
$PN"82"125;
"A15_CAS_N"
$PN"86"126;
"A14_WE_N"
$PN"228"127;
"A11"
$PN"210"128;
"A10"
$PN"225"129;
"DQ<38>"
$PN"102"104;
"DQ<36>"
$PN"95"105;
"DQ<35>"
$PN"249"106;
"A2"
$PN"216"59;
"ALERT_N"
$PN"208"27;
"ACT_N"
$PN"62"26;
"DQ<0>"
$PN"5"72;
"DQ<1>"
$PN"150"73;
"SA<1>"
$PN"140"16;
"SA<2>"
$PN"238"19;
"VDDSPD"
$PN"284"19;
"SA<0>"
$PN"139"16;
"BA<0>"
$PN"81"53;
"BG<1>"
$PN"207"54;
"BG<0>"
$PN"63"55;
"CK1P"
$PN"218"56;
"VREFCA"
$PN"146"22;
"SDA"
$PN"285"29;
"SCL"
$PN"141"28;
"RFU<2>"
$PN"144"25;
"RESET_N"
$PN"58"31;
"PAR"
$PN"222"33;
"EVENT_N"
$PN"78"32;
"DQ<6>"
$PN"10"75;
"DQ<7>"
$PN"155"76;
"DQ<8>"
$PN"16"77;
"DQ<9>"
$PN"161"78;
"DQ<10>"
$PN"23"82;
"DQ<11>"
$PN"168"79;
"DQ<12>"
$PN"14"83;
"DQ<13>"
$PN"159"80;
"DQ<14>"
$PN"21"81;
"DQ<16>"
$PN"27"86;
"DQ<18>"
$PN"34"90;
"DQ<19>"
$PN"179"91;
"DQ<20>"
$PN"25"92;
"DQ<21>"
$PN"170"87;
"DQ<22>"
$PN"32"88;
"DQ<23>"
$PN"177"89;
"DQ<24>"
$PN"38"93;
"DQ<25>"
$PN"183"96;
"DQ<30>"
$PN"43"97;
"DQ<31>"
$PN"188"98;
"DQ<32>"
$PN"97"99;
"DQ<33>"
$PN"242"100;
"DQ<34>"
$PN"104"101;
"DQ<37>"
$PN"240"107;
"DQ<39>"
$PN"247"108;
"DQ<40>"
$PN"108"109;
"DQ<41>"
$PN"253"110;
"DQ<42>"
$PN"115"111;
"DQ<43>"
$PN"260"112;
"DQ<44>"
$PN"106"113;
"DQ<45>"
$PN"251"114;
"DQ<46>"
$PN"113"123;
"DQ<55>"
$PN"269"124;
"DQ<56>"
$PN"130"138;
"DQ<59>"
$PN"282"139;
"DQ<60>"
$PN"128"140;
"CKE<1>"
$PN"203"48;
"CK0N"
$PN"75"34;
"CB<0>"
$PN"49"38;
"CB<1>"
$PN"194"39;
"CB<2>"
$PN"56"40;
"CB<3>"
$PN"201"41;
"CB<4>"
$PN"47"42;
"CB<5>"
$PN"192"43;
"CB<6>"
$PN"54"44;
"A9"
$PN"66"60;
"A8"
$PN"68"61;
"A7"
$PN"211"62;
"A6"
$PN"69"63;
"A5"
$PN"213"64;
"A4"
$PN"214"65;
"A3"
$PN"71"66;
"A17"
$PN"234"130;
"A13"
$PN"232"131;
"A12"
$PN"65"132;
"A1"
$PN"72"67;
"A0"
$PN"79"68;
"C<2>"
$PN"235"52;
"DQ<28>"
$PN"36"102;
"DQ<29>"
$PN"181"103;
"S1_N"
$PN"89"49;
"S2_N_C<0>"
$PN"93"50;
"S3_N_C<1>"
$PN"237"51;
"CK0P"
$PN"74"57;
"CK1N"
$PN"219"35;
"BA<1>"
$PN"224"58;
%"TAP"
"6","(-3050,4475)","0","mstr_standard","I112";
;
HDL_TAP"TRUE"
BODY_TYPE"PLUMBING"
CDS_LIB"mstr_standard";
"B \NAC \NWC"4;
"S \NAC"
BN"17"130;
%"TAP"
"6","(-3050,4425)","0","mstr_standard","I113";
;
HDL_TAP"TRUE"
BODY_TYPE"PLUMBING"
CDS_LIB"mstr_standard";
"B \NAC \NWC"4;
"S \NAC"
BN"16"125;
%"TAP"
"6","(-3050,4375)","0","mstr_standard","I114";
;
HDL_TAP"TRUE"
BODY_TYPE"PLUMBING"
CDS_LIB"mstr_standard";
"B \NAC \NWC"4;
"S \NAC"
BN"15"126;
%"TAP"
"6","(-3050,4325)","0","mstr_standard","I115";
;
HDL_TAP"TRUE"
BODY_TYPE"PLUMBING"
CDS_LIB"mstr_standard";
"B \NAC \NWC"4;
"S \NAC"
BN"14"127;
%"TAP"
"6","(-3050,4275)","0","mstr_standard","I116";
;
HDL_TAP"TRUE"
BODY_TYPE"PLUMBING"
CDS_LIB"mstr_standard";
"B \NAC \NWC"4;
"S \NAC"
BN"13"131;
%"TAP"
"6","(-3050,4225)","0","mstr_standard","I117";
;
HDL_TAP"TRUE"
BODY_TYPE"PLUMBING"
CDS_LIB"mstr_standard";
"B \NAC \NWC"4;
"S \NAC"
BN"12"132;
%"TAP"
"6","(-3050,4175)","0","mstr_standard","I118";
;
HDL_TAP"TRUE"
BODY_TYPE"PLUMBING"
CDS_LIB"mstr_standard";
"B \NAC \NWC"4;
"S \NAC"
BN"11"128;
%"TAP"
"6","(-3050,4125)","0","mstr_standard","I119";
;
HDL_TAP"TRUE"
BODY_TYPE"PLUMBING"
CDS_LIB"mstr_standard";
"B \NAC \NWC"4;
"S \NAC"
BN"10"129;
%"TAP"
"6","(650,4900)","2","mstr_standard","I12";
;
HDL_TAP"TRUE"
BODY_TYPE"PLUMBING"
CDS_LIB"mstr_standard";
"B \NAC \NWC"1;
"S \NAC"
BN"14"165;
%"TAP"
"6","(-3050,4075)","0","mstr_standard","I120";
;
HDL_TAP"TRUE"
BODY_TYPE"PLUMBING"
CDS_LIB"mstr_standard";
"B \NAC \NWC"4;
"S \NAC"
BN"9"60;
%"TAP"
"6","(-3050,4025)","0","mstr_standard","I121";
;
HDL_TAP"TRUE"
BODY_TYPE"PLUMBING"
CDS_LIB"mstr_standard";
"B \NAC \NWC"4;
"S \NAC"
BN"8"61;
%"TAP"
"6","(-3050,3975)","0","mstr_standard","I122";
;
HDL_TAP"TRUE"
BODY_TYPE"PLUMBING"
CDS_LIB"mstr_standard";
"B \NAC \NWC"4;
"S \NAC"
BN"7"62;
%"TAP"
"6","(-3050,3925)","0","mstr_standard","I123";
;
HDL_TAP"TRUE"
BODY_TYPE"PLUMBING"
CDS_LIB"mstr_standard";
"B \NAC \NWC"4;
"S \NAC"
BN"6"63;
%"TAP"
"6","(-3050,3875)","0","mstr_standard","I124";
;
HDL_TAP"TRUE"
BODY_TYPE"PLUMBING"
CDS_LIB"mstr_standard";
"B \NAC \NWC"4;
"S \NAC"
BN"5"64;
%"TAP"
"6","(-3050,3825)","0","mstr_standard","I125";
;
HDL_TAP"TRUE"
BODY_TYPE"PLUMBING"
CDS_LIB"mstr_standard";
"B \NAC \NWC"4;
"S \NAC"
BN"4"65;
%"TAP"
"6","(-3050,3775)","0","mstr_standard","I126";
;
HDL_TAP"TRUE"
BODY_TYPE"PLUMBING"
CDS_LIB"mstr_standard";
"B \NAC \NWC"4;
"S \NAC"
BN"3"66;
%"TAP"
"6","(-3050,3725)","0","mstr_standard","I127";
;
HDL_TAP"TRUE"
BODY_TYPE"PLUMBING"
CDS_LIB"mstr_standard";
"B \NAC \NWC"4;
"S \NAC"
BN"2"59;
%"TAP"
"6","(-3050,3675)","0","mstr_standard","I128";
;
HDL_TAP"TRUE"
BODY_TYPE"PLUMBING"
CDS_LIB"mstr_standard";
"B \NAC \NWC"4;
"S \NAC"
BN"1"67;
%"TAP"
"6","(-3050,3625)","0","mstr_standard","I129";
;
HDL_TAP"TRUE"
BODY_TYPE"PLUMBING"
CDS_LIB"mstr_standard";
"B \NAC \NWC"4;
"S \NAC"
BN"0"68;
%"TAP"
"6","(650,4800)","2","mstr_standard","I13";
;
HDL_TAP"TRUE"
BODY_TYPE"PLUMBING"
CDS_LIB"mstr_standard";
"B \NAC \NWC"1;
"S \NAC"
BN"13"167;
%"TAP"
"6","(-3050,3525)","0","mstr_standard","I130";
;
HDL_TAP"TRUE"
BODY_TYPE"PLUMBING"
CDS_LIB"mstr_standard";
"B \NAC \NWC"7;
"S \NAC"
BN"1"58;
%"TAP"
"6","(-3050,3475)","0","mstr_standard","I133";
;
HDL_TAP"TRUE"
BODY_TYPE"PLUMBING"
CDS_LIB"mstr_standard";
"B \NAC \NWC"7;
"S \NAC"
BN"0"53;
%"TAP"
"6","(-3050,3425)","0","mstr_standard","I134";
;
HDL_TAP"TRUE"
BODY_TYPE"PLUMBING"
CDS_LIB"mstr_standard";
"B \NAC \NWC"6;
"S \NAC"
BN"1"54;
%"TAP"
"6","(-3050,3375)","0","mstr_standard","I135";
;
HDL_TAP"TRUE"
BODY_TYPE"PLUMBING"
CDS_LIB"mstr_standard";
"B \NAC \NWC"6;
"S \NAC"
BN"0"55;
%"TAP"
"6","(-3050,2375)","0","mstr_standard","I138";
;
HDL_TAP"TRUE"
BODY_TYPE"PLUMBING"
CDS_LIB"mstr_standard";
"B \NAC \NWC"10;
"S \NAC"
BN"7"44;
%"TAP"
"6","(-3050,2425)","0","mstr_standard","I139";
;
HDL_TAP"TRUE"
BODY_TYPE"PLUMBING"
CDS_LIB"mstr_standard";
"B \NAC \NWC"10;
"S \NAC"
BN"6"37;
%"TAP"
"6","(650,4600)","2","mstr_standard","I14";
;
HDL_TAP"TRUE"
BODY_TYPE"PLUMBING"
CDS_LIB"mstr_standard";
"B \NAC \NWC"1;
"S \NAC"
BN"11"171;
%"TAP"
"6","(-3050,2325)","0","mstr_standard","I140";
;
HDL_TAP"TRUE"
BODY_TYPE"PLUMBING"
CDS_LIB"mstr_standard";
"B \NAC \NWC"10;
"S \NAC"
BN"4"43;
%"TAP"
"6","(-3050,2275)","0","mstr_standard","I141";
;
HDL_TAP"TRUE"
BODY_TYPE"PLUMBING"
CDS_LIB"mstr_standard";
"B \NAC \NWC"10;
"S \NAC"
BN"5"42;
%"TAP"
"6","(-3050,2225)","0","mstr_standard","I142";
;
HDL_TAP"TRUE"
BODY_TYPE"PLUMBING"
CDS_LIB"mstr_standard";
"B \NAC \NWC"10;
"S \NAC"
BN"2"41;
%"TAP"
"6","(-3050,2175)","0","mstr_standard","I143";
;
HDL_TAP"TRUE"
BODY_TYPE"PLUMBING"
CDS_LIB"mstr_standard";
"B \NAC \NWC"10;
"S \NAC"
BN"3"40;
%"TAP"
"6","(-3050,2125)","0","mstr_standard","I144";
;
HDL_TAP"TRUE"
BODY_TYPE"PLUMBING"
CDS_LIB"mstr_standard";
"B \NAC \NWC"10;
"S \NAC"
BN"0"39;
%"TAP"
"6","(-3050,2075)","0","mstr_standard","I145";
;
HDL_TAP"TRUE"
BODY_TYPE"PLUMBING"
CDS_LIB"mstr_standard";
"B \NAC \NWC"10;
"S \NAC"
BN"1"38;
%"TAP"
"6","(650,4700)","2","mstr_standard","I15";
;
HDL_TAP"TRUE"
BODY_TYPE"PLUMBING"
CDS_LIB"mstr_standard";
"B \NAC \NWC"1;
"S \NAC"
BN"12"169;
%"TAP"
"6","(-3050,3275)","0","mstr_standard","I152";
;
HDL_TAP"TRUE"
BODY_TYPE"PLUMBING"
CDS_LIB"mstr_standard";
"B \NAC \NWC"5;
"S \NAC"
BN"1"56;
%"TAP"
"6","(-3050,3175)","0","mstr_standard","I153";
;
HDL_TAP"TRUE"
BODY_TYPE"PLUMBING"
CDS_LIB"mstr_standard";
"B \NAC \NWC"5;
"S \NAC"
BN"0"57;
%"TAP"
"6","(-3250,3225)","0","mstr_standard","I154";
;
HDL_TAP"TRUE"
BODY_TYPE"PLUMBING"
CDS_LIB"mstr_standard";
"B \NAC \NWC"12;
"S \NAC"
BN"1"35;
%"TAP"
"6","(-3250,3125)","0","mstr_standard","I155";
;
HDL_TAP"TRUE"
BODY_TYPE"PLUMBING"
CDS_LIB"mstr_standard";
"B \NAC \NWC"12;
"S \NAC"
BN"0"34;
%"TAP"
"6","(-3050,2975)","0","mstr_standard","I158";
;
HDL_TAP"TRUE"
BODY_TYPE"PLUMBING"
CDS_LIB"mstr_standard";
"B \NAC \NWC"8;
"S \NAC"
BN"3"51;
%"TAP"
"6","(-3050,2925)","0","mstr_standard","I159";
;
HDL_TAP"TRUE"
BODY_TYPE"PLUMBING"
CDS_LIB"mstr_standard";
"B \NAC \NWC"8;
"S \NAC"
BN"2"50;
%"TAP"
"6","(-3050,2875)","0","mstr_standard","I160";
;
HDL_TAP"TRUE"
BODY_TYPE"PLUMBING"
CDS_LIB"mstr_standard";
"B \NAC \NWC"8;
"S \NAC"
BN"1"49;
%"TAP"
"6","(-3050,2825)","0","mstr_standard","I161";
;
HDL_TAP"TRUE"
BODY_TYPE"PLUMBING"
CDS_LIB"mstr_standard";
"B \NAC \NWC"8;
"S \NAC"
BN"0"45;
%"TAP"
"6","(-3050,2725)","0","mstr_standard","I162";
;
HDL_TAP"TRUE"
BODY_TYPE"PLUMBING"
CDS_LIB"mstr_standard";
"B \NAC \NWC"9;
"S \NAC"
BN"1"48;
%"TAP"
"6","(-3050,2675)","0","mstr_standard","I163";
;
HDL_TAP"TRUE"
BODY_TYPE"PLUMBING"
CDS_LIB"mstr_standard";
"B \NAC \NWC"9;
"S \NAC"
BN"0"46;
%"TAP"
"6","(-3050,2575)","0","mstr_standard","I164";
;
HDL_TAP"TRUE"
BODY_TYPE"PLUMBING"
CDS_LIB"mstr_standard";
"B \NAC \NWC"11;
"S \NAC"
BN"1"47;
%"TAP"
"6","(-3050,2525)","0","mstr_standard","I165";
;
HDL_TAP"TRUE"
BODY_TYPE"PLUMBING"
CDS_LIB"mstr_standard";
"B \NAC \NWC"11;
"S \NAC"
BN"0"36;
%"PVTT_DEF"
"1","(-1100,2750)","0","mstr_symbols","I17";
;
HDL_POWER"PVTT_DEF"
ROOM"DDR4_CH_C"
BODY_TYPE"PLUMBING"
CDS_LIB"mstr_symbols"
BOM_COST"MEM"
VOLTAGE"0.6V";
"G\NAC"13;
%"SCONN288_H44441004"
"4","(-250,2050)","0","mstr_sconn","I171";
;
CDS_SEC"4"
ROOM"DDR4_CH_F"
CDS_LOCATION"J4A1"
SEC"4"
SEC_TYPE"PIP"
CDS_LIB"mstr_sconn"
BOM_COST"MEM"
PACK_TYPE"PIP"
MATERIAL"SCONN"
PART_NUMBER"H44441-004"
LOCATION"J4A1";
"VPP<4>"
$PN"142"18;
"VTT<1>"
$PN"77"13;
"VPP<0>"
$PN"287"18;
"VPP<1>"
$PN"286"18;
"VPP<2>"
$PN"288"18;
"VPP<3>"
$PN"143"18;
"VDD<1>"
$PN"233"14;
"VDD<2>"
$PN"231"14;
"VDD<3>"
$PN"229"14;
"VDD<4>"
$PN"226"14;
"VDD<5>"
$PN"223"14;
"VDD<7>"
$PN"217"14;
"VDD<8>"
$PN"215"14;
"VDD<9>"
$PN"212"14;
"VDD<11>"
$PN"206"14;
"VDD<12>"
$PN"204"14;
"VDD<14>"
$PN"90"14;
"VDD<15>"
$PN"88"14;
"VDD<17>"
$PN"83"14;
"VDD<18>"
$PN"80"14;
"VDD<20>"
$PN"73"14;
"VDD<21>"
$PN"70"14;
"VDD<22>"
$PN"67"14;
"VDD<24>"
$PN"61"14;
"12V<0>"
$PN"145"20;
"12V<1>"
$PN"1"20;
"VTT<0>"
$PN"221"13;
"VDD<25>"
$PN"59"14;
"VDD<23>"
$PN"64"14;
"VDD<19>"
$PN"76"14;
"VDD<16>"
$PN"85"14;
"VDD<13>"
$PN"92"14;
"VDD<10>"
$PN"209"14;
"VDD<6>"
$PN"220"14;
"VDD<0>"
$PN"236"14;
%"PVDDQ_DEF"
"1","(-1275,2600)","0","mstr_symbols","I172";
;
HDL_POWER"PVDDQ_DEF"
ROOM"DDR4_CH_C"
BODY_TYPE"PLUMBING"
CDS_LIB"mstr_symbols"
BOM_COST"MEM"
VOLTAGE"1.2V";
"G\NAC"14;
%"GND"
"1","(2450,1100)","2","mstr_symbols","I173";
;
HDL_POWER"GND"
ROOM"DDR4_CH_C"
BODY_TYPE"PLUMBING"
CDS_LIB"mstr_symbols"
SIZE"1B"
BOM_COST"MEM"
VOLTAGE"0";
"A\NAC"15;
%"GND"
"1","(-5050,1475)","2","mstr_symbols","I175";
;
HDL_POWER"GND"
ROOM"DDR4_CH_C"
BODY_TYPE"PLUMBING"
SIZE"1B"
CDS_LIB"mstr_symbols"
BOM_COST"MEM"
VOLTAGE"0";
"A\NAC"16;
%"CAP_A"
"1","(-4500,1125)","2","dev_discrete","I178";
;
ROOM"DDR4_CH_F"
$SEC"1"
CDS_SEC"1"
CDS_LIB"dev_discrete"
BOM_COST"MEM"
CDS_LOCATION"C6L1"
MATERIAL"X7R"
VOLTAGE"25V"
PACK_TYPE"0402V"
TOLERANCE"10%"
VALUE"0.01UF"
PART_NUMBER"A36096-045"
LOCATION"C6L1";
"B"
$PN"2"17;
"A"
$PN"1"22;
%"GND"
"1","(-4500,875)","0","mstr_symbols","I179";
;
HDL_POWER"GND"
ROOM"DDR4_CH_C"
BODY_TYPE"PLUMBING"
CDS_LIB"mstr_symbols"
SIZE"1B"
BOM_COST"MEM"
VOLTAGE"0";
"A\NAC"17;
%"PVPP_DEF"
"1","(-950,3050)","0","mstr_symbols","I180";
;
HDL_POWER"PVPP_DEF"
ROOM"DDR4_CH_C"
BODY_TYPE"PLUMBING"
CDS_LIB"mstr_symbols"
BOM_COST"MEM"
VOLTAGE"2.5V";
"G\NAC"18;
%"PVPP_DEF"
"1","(-5050,1825)","0","mstr_symbols","I181";
;
HDL_POWER"PVPP_DEF"
ROOM"DDR4_CH_C"
BODY_TYPE"PLUMBING"
CDS_LIB"mstr_symbols"
BOM_COST"MEM"
VOLTAGE"2.5V";
"G\NAC"19;
%"TAP"
"6","(850,4550)","2","mstr_standard","I19";
;
HDL_TAP"TRUE"
BODY_TYPE"PLUMBING"
CDS_LIB"mstr_standard";
"B \NAC \NWC"2;
"S \NAC"
BN"11"172;
%"P12V_NVDIMM_DEF"
"1","(450,3125)","0","mstr_symbols","I195";
;
HDL_POWER"P12V_NVDIMM_DEF"
BODY_TYPE"PLUMBING"
CDS_LIB"mstr_symbols"
VOLTAGE"12.0";
"G\NAC"20;
%"TAP"
"6","(850,4450)","2","mstr_standard","I20";
;
HDL_TAP"TRUE"
BODY_TYPE"PLUMBING"
CDS_LIB"mstr_standard";
"B \NAC \NWC"2;
"S \NAC"
BN"10"174;
%"TAP"
"6","(850,4350)","2","mstr_standard","I21";
;
HDL_TAP"TRUE"
BODY_TYPE"PLUMBING"
CDS_LIB"mstr_standard";
"B \NAC \NWC"2;
"S \NAC"
BN"9"155;
%"TAP"
"6","(850,4250)","2","mstr_standard","I22";
;
HDL_TAP"TRUE"
BODY_TYPE"PLUMBING"
CDS_LIB"mstr_standard";
"B \NAC \NWC"2;
"S \NAC"
BN"8"157;
%"TAP"
"6","(850,4150)","2","mstr_standard","I23";
;
HDL_TAP"TRUE"
BODY_TYPE"PLUMBING"
CDS_LIB"mstr_standard";
"B \NAC \NWC"2;
"S \NAC"
BN"7"159;
%"TAP"
"6","(650,4400)","2","mstr_standard","I24";
;
HDL_TAP"TRUE"
BODY_TYPE"PLUMBING"
CDS_LIB"mstr_standard";
"B \NAC \NWC"1;
"S \NAC"
BN"9"154;
%"TAP"
"6","(650,4500)","2","mstr_standard","I25";
;
HDL_TAP"TRUE"
BODY_TYPE"PLUMBING"
CDS_LIB"mstr_standard";
"B \NAC \NWC"1;
"S \NAC"
BN"10"173;
%"TAP"
"6","(650,4300)","2","mstr_standard","I26";
;
HDL_TAP"TRUE"
BODY_TYPE"PLUMBING"
CDS_LIB"mstr_standard";
"B \NAC \NWC"1;
"S \NAC"
BN"8"156;
%"TAP"
"6","(650,4100)","2","mstr_standard","I27";
;
HDL_TAP"TRUE"
BODY_TYPE"PLUMBING"
CDS_LIB"mstr_standard";
"B \NAC \NWC"1;
"S \NAC"
BN"6"160;
%"TAP"
"6","(650,4200)","2","mstr_standard","I28";
;
HDL_TAP"TRUE"
BODY_TYPE"PLUMBING"
CDS_LIB"mstr_standard";
"B \NAC \NWC"1;
"S \NAC"
BN"7"158;
%"TAP"
"6","(850,4050)","2","mstr_standard","I29";
;
HDL_TAP"TRUE"
BODY_TYPE"PLUMBING"
CDS_LIB"mstr_standard";
"B \NAC \NWC"2;
"S \NAC"
BN"6"141;
%"TAP"
"6","(850,5150)","2","mstr_standard","I3";
;
HDL_TAP"TRUE"
BODY_TYPE"PLUMBING"
CDS_LIB"mstr_standard";
"B \NAC \NWC"2;
"S \NAC"
BN"17"176;
%"TAP"
"6","(850,3950)","2","mstr_standard","I30";
;
HDL_TAP"TRUE"
BODY_TYPE"PLUMBING"
CDS_LIB"mstr_standard";
"B \NAC \NWC"2;
"S \NAC"
BN"5"143;
%"TAP"
"6","(850,3850)","2","mstr_standard","I31";
;
HDL_TAP"TRUE"
BODY_TYPE"PLUMBING"
CDS_LIB"mstr_standard";
"B \NAC \NWC"2;
"S \NAC"
BN"4"145;
%"TAP"
"6","(850,3750)","2","mstr_standard","I32";
;
HDL_TAP"TRUE"
BODY_TYPE"PLUMBING"
CDS_LIB"mstr_standard";
"B \NAC \NWC"2;
"S \NAC"
BN"3"147;
%"TAP"
"6","(850,3650)","2","mstr_standard","I33";
;
HDL_TAP"TRUE"
BODY_TYPE"PLUMBING"
CDS_LIB"mstr_standard";
"B \NAC \NWC"2;
"S \NAC"
BN"2"149;
%"TAP"
"6","(650,3900)","2","mstr_standard","I34";
;
HDL_TAP"TRUE"
BODY_TYPE"PLUMBING"
CDS_LIB"mstr_standard";
"B \NAC \NWC"1;
"S \NAC"
BN"4"144;
%"TAP"
"6","(650,4000)","2","mstr_standard","I35";
;
HDL_TAP"TRUE"
BODY_TYPE"PLUMBING"
CDS_LIB"mstr_standard";
"B \NAC \NWC"1;
"S \NAC"
BN"5"142;
%"TAP"
"6","(650,3800)","2","mstr_standard","I36";
;
HDL_TAP"TRUE"
BODY_TYPE"PLUMBING"
CDS_LIB"mstr_standard";
"B \NAC \NWC"1;
"S \NAC"
BN"3"146;
%"TAP"
"6","(650,3700)","2","mstr_standard","I37";
;
HDL_TAP"TRUE"
BODY_TYPE"PLUMBING"
CDS_LIB"mstr_standard";
"B \NAC \NWC"1;
"S \NAC"
BN"2"148;
%"TAP"
"6","(650,3600)","2","mstr_standard","I38";
;
HDL_TAP"TRUE"
BODY_TYPE"PLUMBING"
CDS_LIB"mstr_standard";
"B \NAC \NWC"1;
"S \NAC"
BN"1"150;
%"TAP"
"6","(850,3450)","2","mstr_standard","I39";
;
HDL_TAP"TRUE"
BODY_TYPE"PLUMBING"
CDS_LIB"mstr_standard";
"B \NAC \NWC"2;
"S \NAC"
BN"0"153;
%"TAP"
"6","(650,5200)","2","mstr_standard","I4";
;
HDL_TAP"TRUE"
BODY_TYPE"PLUMBING"
CDS_LIB"mstr_standard";
"B \NAC \NWC"1;
"S \NAC"
BN"17"175;
%"TAP"
"6","(850,3550)","2","mstr_standard","I40";
;
HDL_TAP"TRUE"
BODY_TYPE"PLUMBING"
CDS_LIB"mstr_standard";
"B \NAC \NWC"2;
"S \NAC"
BN"1"151;
%"TAP"
"6","(650,3500)","2","mstr_standard","I41";
;
HDL_TAP"TRUE"
BODY_TYPE"PLUMBING"
CDS_LIB"mstr_standard";
"B \NAC \NWC"1;
"S \NAC"
BN"0"152;
%"SCONN288_H44441004"
"3","(1750,2400)","0","mstr_sconn","I43";
;
CDS_SEC"3"
ROOM"DDR4_CH_F"
CDS_LOCATION"J4A1"
SEC"3"
SEC_TYPE"PIP"
CDS_LIB"mstr_sconn"
BOM_COST"MEM"
PACK_TYPE"PIP"
MATERIAL"SCONN"
PART_NUMBER"H44441-004"
LOCATION"J4A1";
"VSS<93>"
$PN"2"21;
"VSS<92>"
$PN"4"21;
"VSS<91>"
$PN"6"21;
"VSS<90>"
$PN"9"21;
"VSS<89>"
$PN"11"21;
"VSS<88>"
$PN"13"21;
"VSS<0>"
$PN"283"15;
"VSS<1>"
$PN"281"15;
"VSS<2>"
$PN"279"15;
"VSS<3>"
$PN"276"15;
"VSS<4>"
$PN"274"15;
"VSS<5>"
$PN"272"15;
"VSS<6>"
$PN"270"15;
"VSS<7>"
$PN"268"15;
"VSS<8>"
$PN"265"15;
"VSS<9>"
$PN"263"15;
"VSS<10>"
$PN"261"15;
"VSS<11>"
$PN"259"15;
"VSS<12>"
$PN"257"15;
"VSS<13>"
$PN"254"15;
"VSS<14>"
$PN"252"15;
"VSS<15>"
$PN"250"15;
"VSS<16>"
$PN"248"15;
"VSS<17>"
$PN"246"15;
"VSS<18>"
$PN"243"15;
"VSS<19>"
$PN"241"15;
"VSS<20>"
$PN"239"15;
"VSS<21>"
$PN"202"15;
"VSS<22>"
$PN"200"15;
"VSS<23>"
$PN"198"15;
"VSS<24>"
$PN"195"15;
"VSS<25>"
$PN"193"15;
"VSS<26>"
$PN"191"15;
"VSS<27>"
$PN"189"15;
"VSS<28>"
$PN"187"15;
"VSS<29>"
$PN"184"15;
"VSS<30>"
$PN"182"15;
"VSS<31>"
$PN"180"15;
"VSS<32>"
$PN"178"15;
"VSS<33>"
$PN"176"15;
"VSS<34>"
$PN"173"15;
"VSS<35>"
$PN"171"15;
"VSS<36>"
$PN"169"15;
"VSS<37>"
$PN"167"15;
"VSS<38>"
$PN"165"15;
"VSS<39>"
$PN"162"15;
"VSS<40>"
$PN"160"15;
"VSS<41>"
$PN"158"15;
"VSS<42>"
$PN"156"15;
"VSS<43>"
$PN"154"15;
"VSS<44>"
$PN"151"15;
"VSS<47>"
$PN"138"21;
"VSS<48>"
$PN"136"21;
"VSS<49>"
$PN"134"21;
"VSS<50>"
$PN"131"21;
"VSS<51>"
$PN"129"21;
"VSS<52>"
$PN"127"21;
"VSS<53>"
$PN"125"21;
"VSS<54>"
$PN"123"21;
"VSS<55>"
$PN"120"21;
"VSS<56>"
$PN"118"21;
"VSS<57>"
$PN"116"21;
"VSS<58>"
$PN"114"21;
"VSS<59>"
$PN"112"21;
"VSS<60>"
$PN"109"21;
"VSS<61>"
$PN"107"21;
"VSS<62>"
$PN"105"21;
"VSS<63>"
$PN"103"21;
"VSS<64>"
$PN"101"21;
"VSS<65>"
$PN"98"21;
"VSS<66>"
$PN"96"21;
"VSS<67>"
$PN"94"21;
"VSS<68>"
$PN"57"21;
"VSS<69>"
$PN"55"21;
"VSS<70>"
$PN"53"21;
"VSS<71>"
$PN"50"21;
"VSS<72>"
$PN"48"21;
"VSS<73>"
$PN"46"21;
"VSS<74>"
$PN"44"21;
"VSS<75>"
$PN"42"21;
"VSS<76>"
$PN"39"21;
"VSS<77>"
$PN"37"21;
"VSS<78>"
$PN"35"21;
"VSS<79>"
$PN"33"21;
"VSS<80>"
$PN"31"21;
"VSS<81>"
$PN"28"21;
"VSS<82>"
$PN"26"21;
"VSS<83>"
$PN"24"21;
"VSS<84>"
$PN"22"21;
"VSS<85>"
$PN"20"21;
"VSS<86>"
$PN"17"21;
"VSS<87>"
$PN"15"21;
"VSS<45>"
$PN"149"15;
"VSS<46>"
$PN"147"15;
%"GND"
"1","(1050,1075)","2","mstr_symbols","I44";
;
HDL_POWER"GND"
ROOM"DDR4_CH_C"
BODY_TYPE"PLUMBING"
CDS_LIB"mstr_symbols"
SIZE"1B"
BOM_COST"MEM"
VOLTAGE"0";
"A\NAC"21;
%"TAP"
"6","(-1550,4475)","2","mstr_standard","I46";
;
HDL_TAP"TRUE"
BODY_TYPE"PLUMBING"
CDS_LIB"mstr_standard";
"B \NAC \NWC"3;
"S \NAC"
BN"62"133;
%"TAP"
"6","(-1550,4425)","2","mstr_standard","I47";
;
HDL_TAP"TRUE"
BODY_TYPE"PLUMBING"
CDS_LIB"mstr_standard";
"B \NAC \NWC"3;
"S \NAC"
BN"63"134;
%"TAP"
"6","(-1550,4325)","2","mstr_standard","I48";
;
HDL_TAP"TRUE"
BODY_TYPE"PLUMBING"
CDS_LIB"mstr_standard";
"B \NAC \NWC"3;
"S \NAC"
BN"61"140;
%"TAP"
"6","(-1550,4375)","2","mstr_standard","I49";
;
HDL_TAP"TRUE"
BODY_TYPE"PLUMBING"
CDS_LIB"mstr_standard";
"B \NAC \NWC"3;
"S \NAC"
BN"60"135;
%"TAP"
"6","(850,5050)","2","mstr_standard","I5";
;
HDL_TAP"TRUE"
BODY_TYPE"PLUMBING"
CDS_LIB"mstr_standard";
"B \NAC \NWC"2;
"S \NAC"
BN"16"162;
%"TAP"
"6","(-1550,4275)","2","mstr_standard","I50";
;
HDL_TAP"TRUE"
BODY_TYPE"PLUMBING"
CDS_LIB"mstr_standard";
"B \NAC \NWC"3;
"S \NAC"
BN"58"139;
%"TAP"
"6","(-1550,4175)","2","mstr_standard","I51";
;
HDL_TAP"TRUE"
BODY_TYPE"PLUMBING"
CDS_LIB"mstr_standard";
"B \NAC \NWC"3;
"S \NAC"
BN"56"137;
%"TAP"
"6","(-1550,4225)","2","mstr_standard","I52";
;
HDL_TAP"TRUE"
BODY_TYPE"PLUMBING"
CDS_LIB"mstr_standard";
"B \NAC \NWC"3;
"S \NAC"
BN"59"136;
%"TAP"
"6","(-1550,4125)","2","mstr_standard","I53";
;
HDL_TAP"TRUE"
BODY_TYPE"PLUMBING"
CDS_LIB"mstr_standard";
"B \NAC \NWC"3;
"S \NAC"
BN"57"138;
%"TAP"
"6","(-1550,4075)","2","mstr_standard","I54";
;
HDL_TAP"TRUE"
BODY_TYPE"PLUMBING"
CDS_LIB"mstr_standard";
"B \NAC \NWC"3;
"S \NAC"
BN"54"124;
%"TAP"
"6","(-1550,3975)","2","mstr_standard","I55";
;
HDL_TAP"TRUE"
BODY_TYPE"PLUMBING"
CDS_LIB"mstr_standard";
"B \NAC \NWC"3;
"S \NAC"
BN"52"121;
%"TAP"
"6","(-1550,4025)","2","mstr_standard","I56";
;
HDL_TAP"TRUE"
BODY_TYPE"PLUMBING"
CDS_LIB"mstr_standard";
"B \NAC \NWC"3;
"S \NAC"
BN"55"122;
%"TAP"
"6","(-1550,3925)","2","mstr_standard","I57";
;
HDL_TAP"TRUE"
BODY_TYPE"PLUMBING"
CDS_LIB"mstr_standard";
"B \NAC \NWC"3;
"S \NAC"
BN"53"120;
%"TAP"
"6","(-1550,3875)","2","mstr_standard","I58";
;
HDL_TAP"TRUE"
BODY_TYPE"PLUMBING"
CDS_LIB"mstr_standard";
"B \NAC \NWC"3;
"S \NAC"
BN"50"119;
%"TAP"
"6","(-1550,3825)","2","mstr_standard","I59";
;
HDL_TAP"TRUE"
BODY_TYPE"PLUMBING"
CDS_LIB"mstr_standard";
"B \NAC \NWC"3;
"S \NAC"
BN"51"118;
%"TAP"
"6","(850,4950)","2","mstr_standard","I6";
;
HDL_TAP"TRUE"
BODY_TYPE"PLUMBING"
CDS_LIB"mstr_standard";
"B \NAC \NWC"2;
"S \NAC"
BN"15"164;
%"TAP"
"6","(-1550,3775)","2","mstr_standard","I60";
;
HDL_TAP"TRUE"
BODY_TYPE"PLUMBING"
CDS_LIB"mstr_standard";
"B \NAC \NWC"3;
"S \NAC"
BN"48"117;
%"TAP"
"6","(-1550,3675)","2","mstr_standard","I61";
;
HDL_TAP"TRUE"
BODY_TYPE"PLUMBING"
CDS_LIB"mstr_standard";
"B \NAC \NWC"3;
"S \NAC"
BN"46"115;
%"TAP"
"6","(-1550,3725)","2","mstr_standard","I62";
;
HDL_TAP"TRUE"
BODY_TYPE"PLUMBING"
CDS_LIB"mstr_standard";
"B \NAC \NWC"3;
"S \NAC"
BN"49"116;
%"TAP"
"6","(-1550,3625)","2","mstr_standard","I63";
;
HDL_TAP"TRUE"
BODY_TYPE"PLUMBING"
CDS_LIB"mstr_standard";
"B \NAC \NWC"3;
"S \NAC"
BN"47"123;
%"TAP"
"6","(-1550,3575)","2","mstr_standard","I64";
;
HDL_TAP"TRUE"
BODY_TYPE"PLUMBING"
CDS_LIB"mstr_standard";
"B \NAC \NWC"3;
"S \NAC"
BN"44"114;
%"TAP"
"6","(-1550,3525)","2","mstr_standard","I65";
;
HDL_TAP"TRUE"
BODY_TYPE"PLUMBING"
CDS_LIB"mstr_standard";
"B \NAC \NWC"3;
"S \NAC"
BN"45"113;
%"SCONN288_H44441004"
"2","(-50,4350)","0","mstr_sconn","I66";
;
CDS_SEC"2"
ROOM"DDR4_CH_F"
CDS_LOCATION"J4A1"
SEC"2"
SEC_TYPE"PIP"
CDS_LIB"mstr_sconn"
BOM_COST"MEM"
PACK_TYPE"PIP"
MATERIAL"SCONN"
PART_NUMBER"H44441-004"
LOCATION"J4A1";
"DQS17P"
$PN"51"175;
"DQS9P"
$PN"7"154;
"DQS9N"
$PN"8"155;
"DQS8P"
$PN"197"156;
"DQS8N"
$PN"196"157;
"DQS7P"
$PN"278"158;
"DQS7N"
$PN"277"159;
"DQS6P"
$PN"267"160;
"DQS6N"
$PN"266"141;
"DQS5P"
$PN"256"142;
"DQS5N"
$PN"255"143;
"DQS4P"
$PN"245"144;
"DQS4N"
$PN"244"145;
"DQS3P"
$PN"186"146;
"DQS3N"
$PN"185"147;
"DQS2P"
$PN"175"148;
"DQS2N"
$PN"174"149;
"DQS1P"
$PN"164"150;
"DQS1N"
$PN"163"151;
"DQS17N"
$PN"52"176;
"DQS16P"
$PN"132"161;
"DQS16N"
$PN"133"162;
"DQS15P"
$PN"121"163;
"DQS15N"
$PN"122"164;
"DQS14P"
$PN"110"165;
"DQS14N"
$PN"111"166;
"DQS13P"
$PN"99"167;
"DQS13N"
$PN"100"168;
"DQS12P"
$PN"40"169;
"DQS12N"
$PN"41"170;
"DQS11P"
$PN"29"171;
"DQS11N"
$PN"30"172;
"DQS10P"
$PN"18"173;
"DQS10N"
$PN"19"174;
"DQS0P"
$PN"153"152;
"DQS0N"
$PN"152"153;
%"TAP"
"6","(-1550,3475)","2","mstr_standard","I67";
;
HDL_TAP"TRUE"
BODY_TYPE"PLUMBING"
CDS_LIB"mstr_standard";
"B \NAC \NWC"3;
"S \NAC"
BN"42"112;
%"TAP"
"6","(-1550,3425)","2","mstr_standard","I68";
;
HDL_TAP"TRUE"
BODY_TYPE"PLUMBING"
CDS_LIB"mstr_standard";
"B \NAC \NWC"3;
"S \NAC"
BN"43"111;
%"TAP"
"6","(-1550,3325)","2","mstr_standard","I69";
;
HDL_TAP"TRUE"
BODY_TYPE"PLUMBING"
CDS_LIB"mstr_standard";
"B \NAC \NWC"3;
"S \NAC"
BN"41"109;
%"TAP"
"6","(850,4750)","2","mstr_standard","I7";
;
HDL_TAP"TRUE"
BODY_TYPE"PLUMBING"
CDS_LIB"mstr_standard";
"B \NAC \NWC"2;
"S \NAC"
BN"13"168;
%"TAP"
"6","(-1550,3275)","2","mstr_standard","I70";
;
HDL_TAP"TRUE"
BODY_TYPE"PLUMBING"
CDS_LIB"mstr_standard";
"B \NAC \NWC"3;
"S \NAC"
BN"38"108;
%"TAP"
"6","(-1550,3375)","2","mstr_standard","I71";
;
HDL_TAP"TRUE"
BODY_TYPE"PLUMBING"
CDS_LIB"mstr_standard";
"B \NAC \NWC"3;
"S \NAC"
BN"40"110;
%"TAP"
"6","(-1550,3225)","2","mstr_standard","I72";
;
HDL_TAP"TRUE"
BODY_TYPE"PLUMBING"
CDS_LIB"mstr_standard";
"B \NAC \NWC"3;
"S \NAC"
BN"39"104;
%"TAP"
"6","(-1550,3175)","2","mstr_standard","I73";
;
HDL_TAP"TRUE"
BODY_TYPE"PLUMBING"
CDS_LIB"mstr_standard";
"B \NAC \NWC"3;
"S \NAC"
BN"36"107;
%"TAP"
"6","(-1550,3125)","2","mstr_standard","I74";
;
HDL_TAP"TRUE"
BODY_TYPE"PLUMBING"
CDS_LIB"mstr_standard";
"B \NAC \NWC"3;
"S \NAC"
BN"37"105;
%"TAP"
"6","(-1550,3025)","2","mstr_standard","I75";
;
HDL_TAP"TRUE"
BODY_TYPE"PLUMBING"
CDS_LIB"mstr_standard";
"B \NAC \NWC"3;
"S \NAC"
BN"35"101;
%"TAP"
"6","(-1550,3075)","2","mstr_standard","I76";
;
HDL_TAP"TRUE"
BODY_TYPE"PLUMBING"
CDS_LIB"mstr_standard";
"B \NAC \NWC"3;
"S \NAC"
BN"34"106;
%"TAP"
"6","(-1550,2975)","2","mstr_standard","I77";
;
HDL_TAP"TRUE"
BODY_TYPE"PLUMBING"
CDS_LIB"mstr_standard";
"B \NAC \NWC"3;
"S \NAC"
BN"32"100;
%"TAP"
"6","(-1550,2925)","2","mstr_standard","I78";
;
HDL_TAP"TRUE"
BODY_TYPE"PLUMBING"
CDS_LIB"mstr_standard";
"B \NAC \NWC"3;
"S \NAC"
BN"33"99;
%"TAP"
"6","(-1550,2775)","2","mstr_standard","I79";
;
HDL_TAP"TRUE"
BODY_TYPE"PLUMBING"
CDS_LIB"mstr_standard";
"B \NAC \NWC"3;
"S \NAC"
BN"28"103;
%"TAP"
"6","(850,4850)","2","mstr_standard","I8";
;
HDL_TAP"TRUE"
BODY_TYPE"PLUMBING"
CDS_LIB"mstr_standard";
"B \NAC \NWC"2;
"S \NAC"
BN"14"166;
%"TAP"
"6","(-1550,2875)","2","mstr_standard","I80";
;
HDL_TAP"TRUE"
BODY_TYPE"PLUMBING"
CDS_LIB"mstr_standard";
"B \NAC \NWC"3;
"S \NAC"
BN"30"98;
%"TAP"
"6","(-1550,2825)","2","mstr_standard","I81";
;
HDL_TAP"TRUE"
BODY_TYPE"PLUMBING"
CDS_LIB"mstr_standard";
"B \NAC \NWC"3;
"S \NAC"
BN"31"97;
%"TAP"
"6","(-1550,2675)","2","mstr_standard","I82";
;
HDL_TAP"TRUE"
BODY_TYPE"PLUMBING"
CDS_LIB"mstr_standard";
"B \NAC \NWC"3;
"S \NAC"
BN"26"95;
%"TAP"
"6","(-1550,2725)","2","mstr_standard","I83";
;
HDL_TAP"TRUE"
BODY_TYPE"PLUMBING"
CDS_LIB"mstr_standard";
"B \NAC \NWC"3;
"S \NAC"
BN"29"102;
%"TAP"
"6","(-1550,2625)","2","mstr_standard","I84";
;
HDL_TAP"TRUE"
BODY_TYPE"PLUMBING"
CDS_LIB"mstr_standard";
"B \NAC \NWC"3;
"S \NAC"
BN"27"94;
%"TAP"
"6","(-1550,2525)","2","mstr_standard","I85";
;
HDL_TAP"TRUE"
BODY_TYPE"PLUMBING"
CDS_LIB"mstr_standard";
"B \NAC \NWC"3;
"S \NAC"
BN"25"93;
%"TAP"
"6","(-1550,2575)","2","mstr_standard","I86";
;
HDL_TAP"TRUE"
BODY_TYPE"PLUMBING"
CDS_LIB"mstr_standard";
"B \NAC \NWC"3;
"S \NAC"
BN"24"96;
%"TAP"
"6","(-1550,2425)","2","mstr_standard","I87";
;
HDL_TAP"TRUE"
BODY_TYPE"PLUMBING"
CDS_LIB"mstr_standard";
"B \NAC \NWC"3;
"S \NAC"
BN"23"88;
%"TAP"
"6","(-1550,2475)","2","mstr_standard","I88";
;
HDL_TAP"TRUE"
BODY_TYPE"PLUMBING"
CDS_LIB"mstr_standard";
"B \NAC \NWC"3;
"S \NAC"
BN"22"89;
%"TAP"
"6","(-1550,2375)","2","mstr_standard","I89";
;
HDL_TAP"TRUE"
BODY_TYPE"PLUMBING"
CDS_LIB"mstr_standard";
"B \NAC \NWC"3;
"S \NAC"
BN"20"87;
%"TAP"
"6","(850,4650)","2","mstr_standard","I9";
;
HDL_TAP"TRUE"
BODY_TYPE"PLUMBING"
CDS_LIB"mstr_standard";
"B \NAC \NWC"2;
"S \NAC"
BN"12"170;
%"TAP"
"6","(-1550,2325)","2","mstr_standard","I90";
;
HDL_TAP"TRUE"
BODY_TYPE"PLUMBING"
CDS_LIB"mstr_standard";
"B \NAC \NWC"3;
"S \NAC"
BN"21"92;
%"TAP"
"6","(-1550,2275)","2","mstr_standard","I91";
;
HDL_TAP"TRUE"
BODY_TYPE"PLUMBING"
CDS_LIB"mstr_standard";
"B \NAC \NWC"3;
"S \NAC"
BN"18"91;
%"TAP"
"6","(-1550,2225)","2","mstr_standard","I92";
;
HDL_TAP"TRUE"
BODY_TYPE"PLUMBING"
CDS_LIB"mstr_standard";
"B \NAC \NWC"3;
"S \NAC"
BN"19"90;
%"TAP"
"6","(-1550,2125)","2","mstr_standard","I93";
;
HDL_TAP"TRUE"
BODY_TYPE"PLUMBING"
CDS_LIB"mstr_standard";
"B \NAC \NWC"3;
"S \NAC"
BN"17"86;
%"TAP"
"6","(-1550,2175)","2","mstr_standard","I94";
;
HDL_TAP"TRUE"
BODY_TYPE"PLUMBING"
CDS_LIB"mstr_standard";
"B \NAC \NWC"3;
"S \NAC"
BN"16"84;
%"TAP"
"6","(-1550,2075)","2","mstr_standard","I95";
;
HDL_TAP"TRUE"
BODY_TYPE"PLUMBING"
CDS_LIB"mstr_standard";
"B \NAC \NWC"3;
"S \NAC"
BN"14"85;
%"TAP"
"6","(-1550,2025)","2","mstr_standard","I96";
;
HDL_TAP"TRUE"
BODY_TYPE"PLUMBING"
CDS_LIB"mstr_standard";
"B \NAC \NWC"3;
"S \NAC"
BN"15"81;
%"TAP"
"6","(-1550,1925)","2","mstr_standard","I97";
;
HDL_TAP"TRUE"
BODY_TYPE"PLUMBING"
CDS_LIB"mstr_standard";
"B \NAC \NWC"3;
"S \NAC"
BN"13"83;
%"TAP"
"6","(-1550,1975)","2","mstr_standard","I98";
;
HDL_TAP"TRUE"
BODY_TYPE"PLUMBING"
CDS_LIB"mstr_standard";
"B \NAC \NWC"3;
"S \NAC"
BN"12"80;
%"TAP"
"6","(-1550,1875)","2","mstr_standard","I99";
;
HDL_TAP"TRUE"
BODY_TYPE"PLUMBING"
CDS_LIB"mstr_standard";
"B \NAC \NWC"3;
"S \NAC"
BN"10"79;
END.
